# T6G (Grand Teton) — schematic netlist excerpt (pin names and nets, part order shuffled) for the footprints in the layout excerpt that follows; sources: Cadence DE-HDL packaged netlist, KiCad conversion of 04192023_DAF0TMB3IC0_F0TG_MB_C_brd_V02_OCP.brd

C2673  Q_CAP  22UF 4V 20% X6S  pkg C0402  page 75 : A = PVDD18_S5_P1 ; B = GND
R6778  Q_RES  10K 1% CHIP  pkg 0201LF  page 184 : A = RST_SMB_RT_R1_N ; B = GND
PR59  Q_RES  0 5% CHIP  pkg 0402LF  page 27 : A = SVID_PVDDCR_CPU1_P0_SVC_R ; B = SVID_PVDDCR_CPU1_P0_SVC

(kicad_pcb
	(version 20260206)
	(generator "pcbnew")
	(generator_version "10.0")
	(general
		(thickness 1.6)
		(legacy_teardrops no)
	)
	(paper "A4")
	(title_block
		(title "04192023_DAF0TMB3IC0_F0TG_MB_C_brd_V02_OCP.brd")
		(comment 1 "Grand Teton / footprints 5254-5256 of 8354")
	)
	(layers
		(0 "F.Cu" signal "TOP")
		(4 "In1.Cu" signal "GND")
		(6 "In2.Cu" signal "IN1")
		(8 "In3.Cu" signal "GND1")
		(10 "In4.Cu" signal "IN2")
		(12 "In5.Cu" signal "GND2")
		(14 "In6.Cu" signal "IN3")
		(16 "In7.Cu" signal "GND3")
		(18 "In8.Cu" signal "VCC")
		(20 "In9.Cu" signal "VCC1")
		(22 "In10.Cu" signal "GND4")
		(24 "In11.Cu" signal "IN4")
		(26 "In12.Cu" signal "GND5")
		(28 "In13.Cu" signal "IN5")
		(30 "In14.Cu" signal "GND6")
		(32 "In15.Cu" signal "IN6")
		(34 "In16.Cu" signal "GND7")
		(2 "B.Cu" signal "BOTTOM")
		(9 "F.Adhes" user "F.Adhesive")
		(11 "B.Adhes" user "B.Adhesive")
		(13 "F.Paste" user "Package Geometry/Pastemask Top")
		(15 "B.Paste" user "Package Geometry/Pastemask Bottom")
		(5 "F.SilkS" user "Ref Des/Silkscreen Top")
		(7 "B.SilkS" user "Ref Des/Silkscreen Bottom")
		(1 "F.Mask" user "Board Geometry/Soldermask Top")
		(3 "B.Mask" user "Board Geometry/Soldermask Bottom")
		(17 "Dwgs.User" user "User.Drawings")
		(19 "Cmts.User" user "User.Comments")
		(21 "Eco1.User" user "User.Eco1")
		(23 "Eco2.User" user "User.Eco2")
		(25 "Edge.Cuts" user "Board Geometry/Outline")
		(27 "Margin" user)
		(31 "F.CrtYd" user "Package Geometry/Place Bound Top")
		(29 "B.CrtYd" user "Package Geometry/Place Bound Bottom")
		(35 "F.Fab" user "Ref Des/Assembly Top")
		(33 "B.Fab" user "Ref Des/Assembly Bottom")
	)
	(footprint ""
		(layer "B.Cu")
		(at 101.033834 -250.892564 180)
		(property "Reference" "C2673"
			(at 0 0 0)
			(layer "B.SilkS")
			(hide yes)
			(effects
				(font
					(size 1.27 1.27)
				)
				(justify mirror)
			)
		)
		(property "Value" ""
			(at 0 0 0)
			(layer "B.Fab")
			(effects
				(font
					(size 1.27 1.27)
				)
				(justify mirror)
			)
		)
		(duplicate_pad_numbers_are_jumpers no)
		(fp_line
			(start 0.7874 0.4064)
			(end 0.7874 -0.4064)
			(stroke
				(width 0.1524)
				(type default)
			)
			(layer "B.SilkS")
		)
		(fp_line
			(start 0.7874 -0.4064)
			(end -0.7874 -0.4064)
			(stroke
				(width 0.1524)
				(type default)
			)
			(layer "B.SilkS")
		)
		(fp_line
			(start -0.7874 0.4064)
			(end 0.7874 0.4064)
			(stroke
				(width 0.1524)
				(type default)
			)
			(layer "B.SilkS")
		)
		(fp_line
			(start -0.7874 -0.4064)
			(end -0.7874 0.4064)
			(stroke
				(width 0.1524)
				(type default)
			)
			(layer "B.SilkS")
		)
		(fp_line
			(start 0.67945 0.3048)
			(end 0.67945 -0.305054)
			(stroke
				(width 0.1)
				(type default)
			)
			(layer "B.Fab")
		)
		(fp_line
			(start 0.67945 -0.305054)
			(end 0.12065 -0.305054)
			(stroke
				(width 0.1)
				(type default)
			)
			(layer "B.Fab")
		)
		(fp_line
			(start 0.12065 0.3048)
			(end 0.67945 0.3048)
			(stroke
				(width 0.1)
				(type default)
			)
			(layer "B.Fab")
		)
		(fp_line
			(start 0.12065 0.2794)
			(end 0.12065 0.3048)
			(stroke
				(width 0.1)
				(type default)
			)
			(layer "B.Fab")
		)
		(fp_line
			(start 0.12065 -0.2794)
			(end -0.12065 -0.2794)
			(stroke
				(width 0.1)
				(type default)
			)
			(layer "B.Fab")
		)
		(fp_line
			(start 0.12065 -0.305054)
			(end 0.12065 -0.2794)
			(stroke
				(width 0.1)
				(type default)
			)
			(layer "B.Fab")
		)
		(fp_line
			(start -0.120396 0.3048)
			(end -0.120396 0.2794)
			(stroke
				(width 0.1)
				(type default)
			)
			(layer "B.Fab")
		)
		(fp_line
			(start -0.120396 0.2794)
			(end 0.12065 0.2794)
			(stroke
				(width 0.1)
				(type default)
			)
			(layer "B.Fab")
		)
		(fp_line
			(start -0.12065 -0.2794)
			(end -0.12065 -0.3048)
			(stroke
				(width 0.1)
				(type default)
			)
			(layer "B.Fab")
		)
		(fp_line
			(start -0.12065 -0.3048)
			(end -0.67945 -0.3048)
			(stroke
				(width 0.1)
				(type default)
			)
			(layer "B.Fab")
		)
		(fp_line
			(start -0.67945 0.3048)
			(end -0.120396 0.3048)
			(stroke
				(width 0.1)
				(type default)
			)
			(layer "B.Fab")
		)
		(fp_line
			(start -0.67945 -0.3048)
			(end -0.67945 0.3048)
			(stroke
				(width 0.1)
				(type default)
			)
			(layer "B.Fab")
		)
		(pad "1" smd circle
			(at 0.40005 0)
			(size 0 0)
			(layers "B.Cu" "B.Mask" "B.Paste")
			(net "PVDD18_S5_P1")
		)
		(pad "2" smd circle
			(at -0.40005 0)
			(size 0 0)
			(layers "B.Cu" "B.Mask" "B.Paste")
			(net "GND")
		)
	)
	(footprint ""
		(layer "B.Cu")
		(at 214.884 -332.74)
		(property "Reference" "R6778"
			(at 0 0 0)
			(layer "B.SilkS")
			(hide yes)
			(effects
				(font
					(size 1.27 1.27)
				)
				(justify mirror)
			)
		)
		(property "Value" ""
			(at 0 0 0)
			(layer "B.Fab")
			(effects
				(font
					(size 1.27 1.27)
				)
				(justify mirror)
			)
		)
		(duplicate_pad_numbers_are_jumpers no)
		(fp_line
			(start -0.32512 -0.175006)
			(end -0.32512 0.175006)
			(stroke
				(width 0.1)
				(type default)
			)
			(layer "B.Fab")
		)
		(fp_line
			(start -0.32512 0.175006)
			(end 0.32512 0.175006)
			(stroke
				(width 0.1)
				(type default)
			)
			(layer "B.Fab")
		)
		(fp_line
			(start 0.32512 -0.175006)
			(end -0.32512 -0.175006)
			(stroke
				(width 0.1)
				(type default)
			)
			(layer "B.Fab")
		)
		(fp_line
			(start 0.32512 0.175006)
			(end 0.32512 -0.175006)
			(stroke
				(width 0.1)
				(type default)
			)
			(layer "B.Fab")
		)
		(pad "1" smd rect
			(at 0.2667 0 180)
			(size 0.3048 0.381)
			(layers "B.Cu" "B.Mask" "B.Paste")
			(net "RST_SMB_RT_R1_N")
		)
		(pad "2" smd rect
			(at -0.2667 0)
			(size 0.3048 0.381)
			(layers "B.Cu" "B.Mask" "B.Paste")
			(net "GND")
		)
	)
	(footprint ""
		(layer "B.Cu")
		(at 341.475314 -310.974486)
		(property "Reference" "PR59"
			(at 0 0 0)
			(layer "B.SilkS")
			(hide yes)
			(effects
				(font
					(size 1.27 1.27)
				)
				(justify mirror)
			)
		)
		(property "Value" ""
			(at 0 0 0)
			(layer "B.Fab")
			(effects
				(font
					(size 1.27 1.27)
				)
				(justify mirror)
			)
		)
		(duplicate_pad_numbers_are_jumpers no)
		(fp_line
			(start -0.7874 -0.4064)
			(end -0.7874 0.4064)
			(stroke
				(width 0.1524)
				(type default)
			)
			(layer "B.SilkS")
		)
		(fp_line
			(start -0.7874 0.4064)
			(end 0.7874 0.4064)
			(stroke
				(width 0.1524)
				(type default)
			)
			(layer "B.SilkS")
		)
		(fp_line
			(start 0.7874 -0.4064)
			(end -0.7874 -0.4064)
			(stroke
				(width 0.1524)
				(type default)
			)
			(layer "B.SilkS")
		)
		(fp_line
			(start 0.7874 0.4064)
			(end 0.7874 -0.4064)
			(stroke
				(width 0.1524)
				(type default)
			)
			(layer "B.SilkS")
		)
		(fp_line
			(start -0.67945 -0.3048)
			(end -0.67945 0.3048)
			(stroke
				(width 0.1)
				(type default)
			)
			(layer "B.Fab")
		)
		(fp_line
			(start -0.67945 0.3048)
			(end -0.120396 0.3048)
			(stroke
				(width 0.1)
				(type default)
			)
			(layer "B.Fab")
		)
		(fp_line
			(start -0.12065 -0.3048)
			(end -0.67945 -0.3048)
			(stroke
				(width 0.1)
				(type default)
			)
			(layer "B.Fab")
		)
		(fp_line
			(start -0.12065 -0.2794)
			(end -0.12065 -0.3048)
			(stroke
				(width 0.1)
				(type default)
			)
			(layer "B.Fab")
		)
		(fp_line
			(start -0.120396 0.2794)
			(end 0.12065 0.2794)
			(stroke
				(width 0.1)
				(type default)
			)
			(layer "B.Fab")
		)
		(fp_line
			(start -0.120396 0.3048)
			(end -0.120396 0.2794)
			(stroke
				(width 0.1)
				(type default)
			)
			(layer "B.Fab")
		)
		(fp_line
			(start 0.12065 -0.305054)
			(end 0.12065 -0.2794)
			(stroke
				(width 0.1)
				(type default)
			)
			(layer "B.Fab")
		)
		(fp_line
			(start 0.12065 -0.2794)
			(end -0.12065 -0.2794)
			(stroke
				(width 0.1)
				(type default)
			)
			(layer "B.Fab")
		)
		(fp_line
			(start 0.12065 0.2794)
			(end 0.12065 0.3048)
			(stroke
				(width 0.1)
				(type default)
			)
			(layer "B.Fab")
		)
		(fp_line
			(start 0.12065 0.3048)
			(end 0.67945 0.3048)
			(stroke
				(width 0.1)
				(type default)
			)
			(layer "B.Fab")
		)
		(fp_line
			(start 0.67945 -0.305054)
			(end 0.12065 -0.305054)
			(stroke
				(width 0.1)
				(type default)
			)
			(layer "B.Fab")
		)
		(fp_line
			(start 0.67945 0.3048)
			(end 0.67945 -0.305054)
			(stroke
				(width 0.1)
				(type default)
			)
			(layer "B.Fab")
		)
		(pad "1" smd circle
			(at 0.40005 0 180)
			(size 0 0)
			(layers "B.Cu" "B.Mask" "B.Paste")
			(net "SVID_PVDDCR_CPU1_P0_SVC_R")
		)
		(pad "2" smd circle
			(at -0.40005 0 180)
			(size 0 0)
			(layers "B.Cu" "B.Mask" "B.Paste")
			(net "SVID_PVDDCR_CPU1_P0_SVC")
		)
	)
)
